# S9S_MB_2U (Grand Teton) — schematic netlist excerpt (pin names and nets, part order shuffled) for the footprints in the layout excerpt that follows; sources: Cadence DE-HDL packaged netlist, KiCad conversion of 03242023_DA0F0TMBIJ0_F0T_Motherboard_J_brd_V01_OCP.brd

R72  Q_RES  196K 1% CHIP  pkg 0402LF  page 113 : A = PD_CHH_CPU1_DIMM2_SAA ; B = GND

(kicad_pcb
	(version 20260206)
	(generator "pcbnew")
	(generator_version "10.0")
	(general
		(thickness 1.6)
		(legacy_teardrops no)
	)
	(paper "A4")
	(title_block
		(title "03242023_DA0F0TMBIJ0_F0T_Motherboard_J_brd_V01_OCP.brd")
		(comment 1 "Grand Teton / footprints 4923-4923 of 6105")
	)
	(layers
		(0 "F.Cu" signal "TOP")
		(4 "In1.Cu" signal "GND")
		(6 "In2.Cu" signal "IN1")
		(8 "In3.Cu" signal "GND1")
		(10 "In4.Cu" signal "IN2")
		(12 "In5.Cu" signal "GND2")
		(14 "In6.Cu" signal "IN3")
		(16 "In7.Cu" signal "GND3")
		(18 "In8.Cu" signal "VCC")
		(20 "In9.Cu" signal "VCC1")
		(22 "In10.Cu" signal "GND4")
		(24 "In11.Cu" signal "IN4")
		(26 "In12.Cu" signal "GND5")
		(28 "In13.Cu" signal "IN5")
		(30 "In14.Cu" signal "GND6")
		(32 "In15.Cu" signal "IN6")
		(34 "In16.Cu" signal "GND7")
		(2 "B.Cu" signal "BOTTOM")
		(9 "F.Adhes" user "F.Adhesive")
		(11 "B.Adhes" user "B.Adhesive")
		(13 "F.Paste" user "Package Geometry/Pastemask Top")
		(15 "B.Paste" user "Package Geometry/Pastemask Bottom")
		(5 "F.SilkS" user "Ref Des/Silkscreen Top")
		(7 "B.SilkS" user "Ref Des/Silkscreen Bottom")
		(1 "F.Mask" user "Board Geometry/Soldermask Top")
		(3 "B.Mask" user "Board Geometry/Soldermask Bottom")
		(17 "Dwgs.User" user "User.Drawings")
		(19 "Cmts.User" user "User.Comments")
		(21 "Eco1.User" user "User.Eco1")
		(23 "Eco2.User" user "User.Eco2")
		(25 "Edge.Cuts" user "Board Geometry/Outline")
		(27 "Margin" user)
		(31 "F.CrtYd" user "Package Geometry/Place Bound Top")
		(29 "B.CrtYd" user "Package Geometry/Place Bound Bottom")
		(35 "F.Fab" user "Ref Des/Assembly Top")
		(33 "B.Fab" user "Ref Des/Assembly Bottom")
	)
	(footprint ""
		(layer "B.Cu")
		(at 205.570582 -318.392048)
		(property "Reference" "R72"
			(at 0 0 0)
			(layer "B.SilkS")
			(hide yes)
			(effects
				(font
					(size 1.27 1.27)
				)
				(justify mirror)
			)
		)
		(property "Value" ""
			(at 0 0 0)
			(layer "B.Fab")
			(effects
				(font
					(size 1.27 1.27)
				)
				(justify mirror)
			)
		)
		(duplicate_pad_numbers_are_jumpers no)
		(fp_line
			(start -0.7874 -0.4064)
			(end -0.7874 0.4064)
			(stroke
				(width 0.1524)
				(type default)
			)
			(layer "B.SilkS")
		)
		(fp_line
			(start -0.7874 0.4064)
			(end 0.7874 0.4064)
			(stroke
				(width 0.1524)
				(type default)
			)
			(layer "B.SilkS")
		)
		(fp_line
			(start 0.7874 -0.4064)
			(end -0.7874 -0.4064)
			(stroke
				(width 0.1524)
				(type default)
			)
			(layer "B.SilkS")
		)
		(fp_line
			(start 0.7874 0.4064)
			(end 0.7874 -0.4064)
			(stroke
				(width 0.1524)
				(type default)
			)
			(layer "B.SilkS")
		)
		(fp_line
			(start -0.67945 -0.3048)
			(end -0.67945 0.3048)
			(stroke
				(width 0.1)
				(type default)
			)
			(layer "B.Fab")
		)
		(fp_line
			(start -0.67945 0.3048)
			(end -0.120396 0.3048)
			(stroke
				(width 0.1)
				(type default)
			)
			(layer "B.Fab")
		)
		(fp_line
			(start -0.12065 -0.3048)
			(end -0.67945 -0.3048)
			(stroke
				(width 0.1)
				(type default)
			)
			(layer "B.Fab")
		)
		(fp_line
			(start -0.12065 -0.2794)
			(end -0.12065 -0.3048)
			(stroke
				(width 0.1)
				(type default)
			)
			(layer "B.Fab")
		)
		(fp_line
			(start -0.120396 0.2794)
			(end 0.12065 0.2794)
			(stroke
				(width 0.1)
				(type default)
			)
			(layer "B.Fab")
		)
		(fp_line
			(start -0.120396 0.3048)
			(end -0.120396 0.2794)
			(stroke
				(width 0.1)
				(type default)
			)
			(layer "B.Fab")
		)
		(fp_line
			(start 0.12065 -0.305054)
			(end 0.12065 -0.2794)
			(stroke
				(width 0.1)
				(type default)
			)
			(layer "B.Fab")
		)
		(fp_line
			(start 0.12065 -0.2794)
			(end -0.12065 -0.2794)
			(stroke
				(width 0.1)
				(type default)
			)
			(layer "B.Fab")
		)
		(fp_line
			(start 0.12065 0.2794)
			(end 0.12065 0.3048)
			(stroke
				(width 0.1)
				(type default)
			)
			(layer "B.Fab")
		)
		(fp_line
			(start 0.12065 0.3048)
			(end 0.67945 0.3048)
			(stroke
				(width 0.1)
				(type default)
			)
			(layer "B.Fab")
		)
		(fp_line
			(start 0.67945 -0.305054)
			(end 0.12065 -0.305054)
			(stroke
				(width 0.1)
				(type default)
			)
			(layer "B.Fab")
		)
		(fp_line
			(start 0.67945 0.3048)
			(end 0.67945 -0.305054)
			(stroke
				(width 0.1)
				(type default)
			)
			(layer "B.Fab")
		)
		(pad "1" smd circle
			(at 0.40005 0 180)
			(size 0 0)
			(layers "B.Cu" "B.Mask" "B.Paste")
			(net "PD_CHH_CPU1_DIMM2_SAA")
		)
		(pad "2" smd circle
			(at -0.40005 0 180)
			(size 0 0)
			(layers "B.Cu" "B.Mask" "B.Paste")
			(net "GND")
		)
	)
)
